#ISCELL
  pure_quanta quanta_title_block_c *
  *
#ISCELL
  standard offpage *
  page306_i1
#ISCELL
  logical_power universal_gnd *
  page306_i10
#CELL
  pure_quanta q_led *
  page306_i11
#CELL
  pure_quanta q_res *
  page306_i12
#CELL
  pure_quanta q_led *
  page306_i13
#CELL
  pure_quanta q_led *
  page306_i14
#CELL
  pure_quanta q_res *
  page306_i15
#CELL
  pure_quanta q_res *
  page306_i16
#ISCELL
  standard offpage *
  page306_i17
#CELL
  pure_quanta mosfet_nch_dual *
  page306_i18
#CELL
  pure_quanta q_led *
  page306_i19
#ISCELL
  standard offpage *
  page306_i2
#CELL
  pure_quanta q_res *
  page306_i20
#ISCELL
  logical_power universal_power *
  page306_i21
#ISCELL
  standard offpage *
  page306_i22
#ISCELL
  logical_power universal_power *
  page306_i24
#ISCELL
  standard offpage *
  page306_i25
#ISCELL
  logical_power universal_power *
  page306_i26
#CELL
  pure_quanta mosfet_nch_dual *
  page306_i27
#ISCELL
  logical_power universal_gnd *
  page306_i28
#ISCELL
  logical_power universal_gnd *
  page306_i29
#CELL
  pure_quanta mosfet_nch_dual *
  page306_i3
#CELL
  pure_quanta q_led *
  page306_i30
#ISCELL
  logical_power universal_gnd *
  page306_i31
#CELL
  pure_quanta q_led *
  page306_i32
#ISCELL
  logical_power universal_power *
  page306_i33
#ISCELL
  standard offpage *
  page306_i34
#CELL
  pure_quanta mosfet_nch_dual *
  page306_i35
#CELL
  pure_quanta q_led *
  page306_i36
#CELL
  pure_quanta q_res *
  page306_i37
#CELL
  pure_quanta q_res *
  page306_i38
#ISCELL
  logical_power universal_power *
  page306_i39
#ISCELL
  logical_power universal_gnd *
  page306_i4
#ISCELL
  logical_power universal_power *
  page306_i40
#CELL
  pure_quanta q_res *
  page306_i41
#ISCELL
  logical_power universal_power *
  page306_i42
#CELL
  pure_quanta mosfet_nch_dual *
  page306_i43
#ISCELL
  logical_power universal_gnd *
  page306_i5
#CELL
  pure_quanta mosfet_nch_dual *
  page306_i6
#ISCELL
  standard offpage *
  page306_i7
#CELL
  pure_quanta mosfet_nch_dual *
  page306_i8
#ISCELL
  logical_power universal_gnd *
  page306_i9
